(kicad_pcb
	(version 20260206)
	(generator "pcbnew")
	(generator_version "10.0")
	(general
		(thickness 1.6)
		(legacy_teardrops no)
	)
	(paper "A4")
	(title_block
		(title "9054_F0T_PDB_BD_GPU_F_V04_1213_1550_OCP.brd")
		(comment 1 "Grand Teton / footprints 46-51 of 608")
	)
	(layers
		(0 "F.Cu" signal "TOP")
		(4 "In1.Cu" signal "GND")
		(6 "In2.Cu" signal "IN1")
		(8 "In3.Cu" signal "GND1")
		(10 "In4.Cu" signal "VCC")
		(12 "In5.Cu" signal "VCC1")
		(14 "In6.Cu" signal "GND2")
		(16 "In7.Cu" signal "IN2")
		(18 "In8.Cu" signal "GND3")
		(2 "B.Cu" signal "BOTTOM")
		(9 "F.Adhes" user "F.Adhesive")
		(11 "B.Adhes" user "B.Adhesive")
		(13 "F.Paste" user "Package Geometry/Pastemask Top")
		(15 "B.Paste" user "Package Geometry/Pastemask Bottom")
		(5 "F.SilkS" user "Ref Des/Silkscreen Top")
		(7 "B.SilkS" user "Ref Des/Silkscreen Bottom")
		(1 "F.Mask" user "Board Geometry/Soldermask Top")
		(3 "B.Mask" user "Board Geometry/Soldermask Bottom")
		(17 "Dwgs.User" user "User.Drawings")
		(19 "Cmts.User" user "User.Comments")
		(21 "Eco1.User" user "User.Eco1")
		(23 "Eco2.User" user "User.Eco2")
		(25 "Edge.Cuts" user "Board Geometry/Outline")
		(27 "Margin" user)
		(31 "F.CrtYd" user "Package Geometry/Place Bound Top")
		(29 "B.CrtYd" user "Package Geometry/Place Bound Bottom")
		(35 "F.Fab" user "Ref Des/Assembly Top")
		(33 "B.Fab" user "Ref Des/Assembly Bottom")
	)
	(footprint ""
		(layer "F.Cu")
		(at 430.276 -37.592 180)
		(property "Reference" "R135"
			(at 0 0 180)
			(layer "F.SilkS")
			(hide yes)
			(effects
				(font
					(size 1.27 1.27)
				)
			)
		)
		(property "Value" ""
			(at 0 0 180)
			(layer "F.Fab")
			(effects
				(font
					(size 1.27 1.27)
				)
			)
		)
		(duplicate_pad_numbers_are_jumpers no)
		(fp_line
			(start 0.7874 0.4064)
			(end -0.7874 0.4064)
			(stroke
				(width 0.1524)
				(type default)
			)
			(layer "F.SilkS")
		)
		(fp_line
			(start 0.7874 -0.4064)
			(end 0.7874 0.4064)
			(stroke
				(width 0.1524)
				(type default)
			)
			(layer "F.SilkS")
		)
		(fp_line
			(start -0.7874 0.4064)
			(end -0.7874 -0.4064)
			(stroke
				(width 0.1524)
				(type default)
			)
			(layer "F.SilkS")
		)
		(fp_line
			(start -0.7874 -0.4064)
			(end 0.7874 -0.4064)
			(stroke
				(width 0.1524)
				(type default)
			)
			(layer "F.SilkS")
		)
		(fp_line
			(start 0.67945 0.3048)
			(end 0.120396 0.3048)
			(stroke
				(width 0.1)
				(type default)
			)
			(layer "F.Fab")
		)
		(fp_line
			(start 0.67945 -0.3048)
			(end 0.67945 0.3048)
			(stroke
				(width 0.1)
				(type default)
			)
			(layer "F.Fab")
		)
		(fp_line
			(start 0.12065 -0.2794)
			(end 0.12065 -0.3048)
			(stroke
				(width 0.1)
				(type default)
			)
			(layer "F.Fab")
		)
		(fp_line
			(start 0.12065 -0.3048)
			(end 0.67945 -0.3048)
			(stroke
				(width 0.1)
				(type default)
			)
			(layer "F.Fab")
		)
		(fp_line
			(start 0.120396 0.3048)
			(end 0.120396 0.2794)
			(stroke
				(width 0.1)
				(type default)
			)
			(layer "F.Fab")
		)
		(fp_line
			(start 0.120396 0.2794)
			(end -0.12065 0.2794)
			(stroke
				(width 0.1)
				(type default)
			)
			(layer "F.Fab")
		)
		(fp_line
			(start -0.12065 0.3048)
			(end -0.67945 0.3048)
			(stroke
				(width 0.1)
				(type default)
			)
			(layer "F.Fab")
		)
		(fp_line
			(start -0.12065 0.2794)
			(end -0.12065 0.3048)
			(stroke
				(width 0.1)
				(type default)
			)
			(layer "F.Fab")
		)
		(fp_line
			(start -0.12065 -0.2794)
			(end 0.12065 -0.2794)
			(stroke
				(width 0.1)
				(type default)
			)
			(layer "F.Fab")
		)
		(fp_line
			(start -0.12065 -0.305054)
			(end -0.12065 -0.2794)
			(stroke
				(width 0.1)
				(type default)
			)
			(layer "F.Fab")
		)
		(fp_line
			(start -0.67945 0.3048)
			(end -0.67945 -0.305054)
			(stroke
				(width 0.1)
				(type default)
			)
			(layer "F.Fab")
		)
		(fp_line
			(start -0.67945 -0.305054)
			(end -0.12065 -0.305054)
			(stroke
				(width 0.1)
				(type default)
			)
			(layer "F.Fab")
		)
		(pad "1" smd circle
			(at -0.40005 0 180)
			(size 0 0)
			(layers "F.Cu" "F.Mask" "F.Paste")
			(net "P3V3_AUX")
		)
		(pad "2" smd circle
			(at 0.40005 0 180)
			(size 0 0)
			(layers "F.Cu" "F.Mask" "F.Paste")
			(net "BOARD_ID_0")
		)
	)
	(footprint ""
		(layer "F.Cu")
		(at 112.988852 -66.6496 -90)
		(property "Reference" "PR6971"
			(at 0 0 270)
			(layer "F.SilkS")
			(hide yes)
			(effects
				(font
					(size 1.27 1.27)
				)
			)
		)
		(property "Value" ""
			(at 0 0 270)
			(layer "F.Fab")
			(effects
				(font
					(size 1.27 1.27)
				)
			)
		)
		(duplicate_pad_numbers_are_jumpers no)
		(fp_line
			(start -1.2954 0.5842)
			(end -1.2954 -0.5842)
			(stroke
				(width 0.1524)
				(type default)
			)
			(layer "F.SilkS")
		)
		(fp_line
			(start 1.2954 0.5842)
			(end -1.2954 0.5842)
			(stroke
				(width 0.1524)
				(type default)
			)
			(layer "F.SilkS")
		)
		(fp_line
			(start -1.2954 -0.5842)
			(end 1.2954 -0.5842)
			(stroke
				(width 0.1524)
				(type default)
			)
			(layer "F.SilkS")
		)
		(fp_line
			(start 1.2954 -0.5842)
			(end 1.2954 0.5842)
			(stroke
				(width 0.1524)
				(type default)
			)
			(layer "F.SilkS")
		)
		(fp_line
			(start -0.8636 0.4572)
			(end -0.8636 0.4318)
			(stroke
				(width 0.1)
				(type default)
			)
			(layer "F.Fab")
		)
		(fp_line
			(start 0.8636 0.4572)
			(end -0.8636 0.4572)
			(stroke
				(width 0.1)
				(type default)
			)
			(layer "F.Fab")
		)
		(fp_line
			(start -0.8636 0.4318)
			(end -0.8636 0.4064)
			(stroke
				(width 0.1)
				(type default)
			)
			(layer "F.Fab")
		)
		(fp_line
			(start -1.1938 0.4064)
			(end -1.1938 -0.406654)
			(stroke
				(width 0.1)
				(type default)
			)
			(layer "F.Fab")
		)
		(fp_line
			(start -0.8636 0.4064)
			(end -1.1938 0.4064)
			(stroke
				(width 0.1)
				(type default)
			)
			(layer "F.Fab")
		)
		(fp_line
			(start 0.8636 0.4064)
			(end 0.8636 0.4572)
			(stroke
				(width 0.1)
				(type default)
			)
			(layer "F.Fab")
		)
		(fp_line
			(start 1.1938 0.4064)
			(end 0.8636 0.4064)
			(stroke
				(width 0.1)
				(type default)
			)
			(layer "F.Fab")
		)
		(fp_line
			(start -1.1938 -0.406654)
			(end -0.8636 -0.406654)
			(stroke
				(width 0.1)
				(type default)
			)
			(layer "F.Fab")
		)
		(fp_line
			(start -0.8636 -0.406654)
			(end -0.8636 -0.4572)
			(stroke
				(width 0.1)
				(type default)
			)
			(layer "F.Fab")
		)
		(fp_line
			(start 0.8636 -0.406654)
			(end 1.1938 -0.406654)
			(stroke
				(width 0.1)
				(type default)
			)
			(layer "F.Fab")
		)
		(fp_line
			(start 1.1938 -0.406654)
			(end 1.1938 0.4064)
			(stroke
				(width 0.1)
				(type default)
			)
			(layer "F.Fab")
		)
		(fp_line
			(start -0.8636 -0.4572)
			(end 0.8636 -0.4572)
			(stroke
				(width 0.1)
				(type default)
			)
			(layer "F.Fab")
		)
		(fp_line
			(start 0.8636 -0.4572)
			(end 0.8636 -0.406654)
			(stroke
				(width 0.1)
				(type default)
			)
			(layer "F.Fab")
		)
		(pad "1" smd rect
			(at -0.7366 0 180)
			(size 0.7112 0.8128)
			(layers "F.Cu" "F.Mask" "F.Paste")
			(net "P52V_HS2_GATE1_R")
		)
		(pad "2" smd rect
			(at 0.7366 0 180)
			(size 0.7112 0.8128)
			(layers "F.Cu" "F.Mask" "F.Paste")
			(net "P52V_HS2_GATE2")
		)
	)
	(footprint ""
		(layer "F.Cu")
		(at 440.309 -51.181 180)
		(property "Reference" "R386"
			(at 0 0 180)
			(layer "F.SilkS")
			(hide yes)
			(effects
				(font
					(size 1.27 1.27)
				)
			)
		)
		(property "Value" ""
			(at 0 0 180)
			(layer "F.Fab")
			(effects
				(font
					(size 1.27 1.27)
				)
			)
		)
		(duplicate_pad_numbers_are_jumpers no)
		(fp_line
			(start 0.7874 0.4064)
			(end -0.7874 0.4064)
			(stroke
				(width 0.1524)
				(type default)
			)
			(layer "F.SilkS")
		)
		(fp_line
			(start 0.7874 -0.4064)
			(end 0.7874 0.4064)
			(stroke
				(width 0.1524)
				(type default)
			)
			(layer "F.SilkS")
		)
		(fp_line
			(start -0.7874 0.4064)
			(end -0.7874 -0.4064)
			(stroke
				(width 0.1524)
				(type default)
			)
			(layer "F.SilkS")
		)
		(fp_line
			(start -0.7874 -0.4064)
			(end 0.7874 -0.4064)
			(stroke
				(width 0.1524)
				(type default)
			)
			(layer "F.SilkS")
		)
		(fp_line
			(start 0.67945 0.3048)
			(end 0.120396 0.3048)
			(stroke
				(width 0.1)
				(type default)
			)
			(layer "F.Fab")
		)
		(fp_line
			(start 0.67945 -0.3048)
			(end 0.67945 0.3048)
			(stroke
				(width 0.1)
				(type default)
			)
			(layer "F.Fab")
		)
		(fp_line
			(start 0.12065 -0.2794)
			(end 0.12065 -0.3048)
			(stroke
				(width 0.1)
				(type default)
			)
			(layer "F.Fab")
		)
		(fp_line
			(start 0.12065 -0.3048)
			(end 0.67945 -0.3048)
			(stroke
				(width 0.1)
				(type default)
			)
			(layer "F.Fab")
		)
		(fp_line
			(start 0.120396 0.3048)
			(end 0.120396 0.2794)
			(stroke
				(width 0.1)
				(type default)
			)
			(layer "F.Fab")
		)
		(fp_line
			(start 0.120396 0.2794)
			(end -0.12065 0.2794)
			(stroke
				(width 0.1)
				(type default)
			)
			(layer "F.Fab")
		)
		(fp_line
			(start -0.12065 0.3048)
			(end -0.67945 0.3048)
			(stroke
				(width 0.1)
				(type default)
			)
			(layer "F.Fab")
		)
		(fp_line
			(start -0.12065 0.2794)
			(end -0.12065 0.3048)
			(stroke
				(width 0.1)
				(type default)
			)
			(layer "F.Fab")
		)
		(fp_line
			(start -0.12065 -0.2794)
			(end 0.12065 -0.2794)
			(stroke
				(width 0.1)
				(type default)
			)
			(layer "F.Fab")
		)
		(fp_line
			(start -0.12065 -0.305054)
			(end -0.12065 -0.2794)
			(stroke
				(width 0.1)
				(type default)
			)
			(layer "F.Fab")
		)
		(fp_line
			(start -0.67945 0.3048)
			(end -0.67945 -0.305054)
			(stroke
				(width 0.1)
				(type default)
			)
			(layer "F.Fab")
		)
		(fp_line
			(start -0.67945 -0.305054)
			(end -0.12065 -0.305054)
			(stroke
				(width 0.1)
				(type default)
			)
			(layer "F.Fab")
		)
		(pad "1" smd circle
			(at -0.40005 0 180)
			(size 0 0)
			(layers "F.Cu" "F.Mask" "F.Paste")
			(net "PWRGD_P3V3_AUX_MB_BUF_N")
		)
		(pad "2" smd circle
			(at 0.40005 0 180)
			(size 0 0)
			(layers "F.Cu" "F.Mask" "F.Paste")
			(net "P3V3_AUX")
		)
	)
	(footprint ""
		(layer "F.Cu")
		(at 174.2694 -47.752)
		(property "Reference" "U23"
			(at -4.24307 1.16967 0)
			(unlocked yes)
			(layer "F.SilkS")
			(effects
				(font
					(size 0.7874 0.5842)
					(thickness 0.1524)
				)
				(justify left)
			)
		)
		(property "Value" ""
			(at 0 0 0)
			(layer "F.Fab")
			(effects
				(font
					(size 1.27 1.27)
				)
			)
		)
		(duplicate_pad_numbers_are_jumpers no)
		(fp_line
			(start -1.603248 -1.500124)
			(end 1.603248 -1.500124)
			(stroke
				(width 0.1524)
				(type default)
			)
			(layer "F.SilkS")
		)
		(fp_line
			(start -1.603248 1.500124)
			(end -1.603248 -1.500124)
			(stroke
				(width 0.1524)
				(type default)
			)
			(layer "F.SilkS")
		)
		(fp_line
			(start 1.603248 -1.500124)
			(end 1.603248 1.500124)
			(stroke
				(width 0.1524)
				(type default)
			)
			(layer "F.SilkS")
		)
		(fp_line
			(start 1.603248 1.500124)
			(end -1.603248 1.500124)
			(stroke
				(width 0.1524)
				(type default)
			)
			(layer "F.SilkS")
		)
		(fp_line
			(start -1.249934 -1.169924)
			(end -1.249934 -0.729996)
			(stroke
				(width 0.1)
				(type default)
			)
			(layer "F.Fab")
		)
		(fp_line
			(start -1.249934 -0.729996)
			(end -0.6985 -0.729996)
			(stroke
				(width 0.1)
				(type default)
			)
			(layer "F.Fab")
		)
		(fp_line
			(start -1.249934 0.729996)
			(end -1.249934 1.169924)
			(stroke
				(width 0.1)
				(type default)
			)
			(layer "F.Fab")
		)
		(fp_line
			(start -1.249934 1.169924)
			(end -0.700024 1.169924)
			(stroke
				(width 0.1)
				(type default)
			)
			(layer "F.Fab")
		)
		(fp_line
			(start -0.700024 -1.500124)
			(end -0.700024 -1.169924)
			(stroke
				(width 0.1)
				(type default)
			)
			(layer "F.Fab")
		)
		(fp_line
			(start -0.700024 -1.169924)
			(end -1.249934 -1.169924)
			(stroke
				(width 0.1)
				(type default)
			)
			(layer "F.Fab")
		)
		(fp_line
			(start -0.700024 1.169924)
			(end -0.700024 1.500124)
			(stroke
				(width 0.1)
				(type default)
			)
			(layer "F.Fab")
		)
		(fp_line
			(start -0.700024 1.500124)
			(end 0.700024 1.500124)
			(stroke
				(width 0.1)
				(type default)
			)
			(layer "F.Fab")
		)
		(fp_line
			(start -0.6985 -0.729996)
			(end -0.6985 0.729996)
			(stroke
				(width 0.1)
				(type default)
			)
			(layer "F.Fab")
		)
		(fp_line
			(start -0.6985 0.729996)
			(end -1.249934 0.729996)
			(stroke
				(width 0.1)
				(type default)
			)
			(layer "F.Fab")
		)
		(fp_line
			(start 0.700024 -1.500124)
			(end -0.700024 -1.500124)
			(stroke
				(width 0.1)
				(type default)
			)
			(layer "F.Fab")
		)
		(fp_line
			(start 0.700024 -0.219964)
			(end 0.700024 -1.500124)
			(stroke
				(width 0.1)
				(type default)
			)
			(layer "F.Fab")
		)
		(fp_line
			(start 0.700024 0.219964)
			(end 1.249934 0.219964)
			(stroke
				(width 0.1)
				(type default)
			)
			(layer "F.Fab")
		)
		(fp_line
			(start 0.700024 1.500124)
			(end 0.700024 0.219964)
			(stroke
				(width 0.1)
				(type default)
			)
			(layer "F.Fab")
		)
		(fp_line
			(start 1.249934 -0.219964)
			(end 0.700024 -0.219964)
			(stroke
				(width 0.1)
				(type default)
			)
			(layer "F.Fab")
		)
		(fp_line
			(start 1.249934 0.219964)
			(end 1.249934 -0.219964)
			(stroke
				(width 0.1)
				(type default)
			)
			(layer "F.Fab")
		)
		(fp_rect
			(start -0.700024 1.500124)
			(end 0.700024 -1.500124)
			(stroke
				(width 0)
				(type default)
			)
			(fill no)
			(layer "F.Fab")
		)
		(pad "D" smd rect
			(at 0.999998 0 270)
			(size 0.8128 0.9144)
			(layers "F.Cu" "F.Mask" "F.Paste")
			(net "GPU_HSC2_BUF_EN_N")
		)
		(pad "G" smd rect
			(at -0.999998 -0.94996 270)
			(size 0.8128 0.9144)
			(layers "F.Cu" "F.Mask" "F.Paste")
			(net "GPU_HSC_BUF_EN")
		)
		(pad "S" smd rect
			(at -0.999998 0.94996 270)
			(size 0.8128 0.9144)
			(layers "F.Cu" "F.Mask" "F.Paste")
			(net "GND")
		)
	)
	(footprint ""
		(layer "F.Cu")
		(at 323.13626 -63.373 180)
		(property "Reference" "PQ33"
			(at -9.628886 -3.917188 0)
			(unlocked yes)
			(layer "F.SilkS")
			(effects
				(font
					(size 0.7874 0.5842)
					(thickness 0.1524)
				)
				(justify left)
			)
		)
		(property "Value" ""
			(at 0 0 180)
			(layer "F.Fab")
			(effects
				(font
					(size 1.27 1.27)
				)
			)
		)
		(duplicate_pad_numbers_are_jumpers no)
		(fp_line
			(start 7.649972 4.99999)
			(end 7.649972 -4.99999)
			(stroke
				(width 0.1524)
				(type default)
			)
			(layer "F.SilkS")
		)
		(fp_line
			(start 7.649972 -4.99999)
			(end 7.630414 -4.99999)
			(stroke
				(width 0.1524)
				(type default)
			)
			(layer "F.SilkS")
		)
		(fp_line
			(start 7.630414 4.99999)
			(end 7.649972 4.99999)
			(stroke
				(width 0.1524)
				(type default)
			)
			(layer "F.SilkS")
		)
		(fp_line
			(start 5.115814 -4.99999)
			(end -7.649972 -4.99999)
			(stroke
				(width 0.1524)
				(type default)
			)
			(layer "F.SilkS")
		)
		(fp_line
			(start -7.649972 4.99999)
			(end 5.115814 4.99999)
			(stroke
				(width 0.1524)
				(type default)
			)
			(layer "F.SilkS")
		)
		(fp_line
			(start -7.649972 3.3274)
			(end -7.649972 4.99999)
			(stroke
				(width 0.1524)
				(type default)
			)
			(layer "F.SilkS")
		)
		(fp_line
			(start -7.649972 -1.7526)
			(end -7.649972 1.7526)
			(stroke
				(width 0.1524)
				(type default)
			)
			(layer "F.SilkS")
		)
		(fp_line
			(start -7.649972 -4.99999)
			(end -7.649972 -3.3274)
			(stroke
				(width 0.1524)
				(type default)
			)
			(layer "F.SilkS")
		)
		(fp_line
			(start 7.649972 4.99999)
			(end 7.649972 -4.99999)
			(stroke
				(width 0.1)
				(type default)
			)
			(layer "F.Fab")
		)
		(fp_line
			(start 7.649972 -4.99999)
			(end -7.649972 -4.99999)
			(stroke
				(width 0.1)
				(type default)
			)
			(layer "F.Fab")
		)
		(fp_line
			(start -7.649972 4.99999)
			(end 7.649972 4.99999)
			(stroke
				(width 0.1)
				(type default)
			)
			(layer "F.Fab")
		)
		(fp_line
			(start -7.649972 -4.99999)
			(end -7.649972 4.99999)
			(stroke
				(width 0.1)
				(type default)
			)
			(layer "F.Fab")
		)
		(pad "D" smd circle
			(at 2.15011 0 180)
			(size 0 0)
			(layers "F.Cu" "F.Mask" "F.Paste")
			(net "P52V_HS1_DRAIN_1")
		)
		(pad "G" smd rect
			(at -7.050024 -2.54 90)
			(size 1.3208 3.0988)
			(layers "F.Cu" "F.Mask" "F.Paste")
			(net "P52V_HS1_GATE2")
		)
		(pad "S" smd rect
			(at -7.050024 2.54 90)
			(size 1.3208 3.0988)
			(layers "F.Cu" "F.Mask" "F.Paste")
			(net "P52V_HS1")
		)
		(zone
			(layer "F.Cu")
			(hatch none 0.5)
			(connect_pads
				(clearance 0)
			)
			(min_thickness 0.25)
			(keepout
				(tracks not_allowed)
				(vias allowed)
				(pads allowed)
				(copperpour not_allowed)
				(footprints allowed)
			)
			(placement
				(enabled no)
				(sheetname "")
			)
			(fill
				(thermal_gap 0.5)
				(thermal_bridge_width 0.5)
				(island_removal_mode 0)
			)
			(polygon
				(pts
					(xy 317.95466 -58.3946) (xy 330.78166 -58.3946) (xy 330.78166 -60.1218) (xy 328.57186 -60.1218)
					(xy 328.57186 -61.5442) (xy 330.78166 -61.5442) (xy 330.78166 -65.2018) (xy 328.57186 -65.2018)
					(xy 328.57186 -66.6242) (xy 330.78166 -66.6242) (xy 330.78166 -68.3514) (xy 317.95466 -68.3514)
					(xy 317.95466 -67.183) (xy 324.15226 -67.183) (xy 324.15226 -59.563) (xy 317.95466 -59.563)
				)
			)
		)
	)
	(footprint ""
		(layer "F.Cu")
		(at 129.612136 -81.788)
		(property "Reference" "PR6995"
			(at 0 0 0)
			(layer "F.SilkS")
			(hide yes)
			(effects
				(font
					(size 1.27 1.27)
				)
			)
		)
		(property "Value" ""
			(at 0 0 0)
			(layer "F.Fab")
			(effects
				(font
					(size 1.27 1.27)
				)
			)
		)
		(duplicate_pad_numbers_are_jumpers no)
		(fp_line
			(start -0.7874 -0.4064)
			(end 0.7874 -0.4064)
			(stroke
				(width 0.1524)
				(type default)
			)
			(layer "F.SilkS")
		)
		(fp_line
			(start -0.7874 0.4064)
			(end -0.7874 -0.4064)
			(stroke
				(width 0.1524)
				(type default)
			)
			(layer "F.SilkS")
		)
		(fp_line
			(start 0.7874 -0.4064)
			(end 0.7874 0.4064)
			(stroke
				(width 0.1524)
				(type default)
			)
			(layer "F.SilkS")
		)
		(fp_line
			(start 0.7874 0.4064)
			(end -0.7874 0.4064)
			(stroke
				(width 0.1524)
				(type default)
			)
			(layer "F.SilkS")
		)
		(fp_line
			(start -0.67945 -0.305054)
			(end -0.12065 -0.305054)
			(stroke
				(width 0.1)
				(type default)
			)
			(layer "F.Fab")
		)
		(fp_line
			(start -0.67945 0.3048)
			(end -0.67945 -0.305054)
			(stroke
				(width 0.1)
				(type default)
			)
			(layer "F.Fab")
		)
		(fp_line
			(start -0.12065 -0.305054)
			(end -0.12065 -0.2794)
			(stroke
				(width 0.1)
				(type default)
			)
			(layer "F.Fab")
		)
		(fp_line
			(start -0.12065 -0.2794)
			(end 0.12065 -0.2794)
			(stroke
				(width 0.1)
				(type default)
			)
			(layer "F.Fab")
		)
		(fp_line
			(start -0.12065 0.2794)
			(end -0.12065 0.3048)
			(stroke
				(width 0.1)
				(type default)
			)
			(layer "F.Fab")
		)
		(fp_line
			(start -0.12065 0.3048)
			(end -0.67945 0.3048)
			(stroke
				(width 0.1)
				(type default)
			)
			(layer "F.Fab")
		)
		(fp_line
			(start 0.120396 0.2794)
			(end -0.12065 0.2794)
			(stroke
				(width 0.1)
				(type default)
			)
			(layer "F.Fab")
		)
		(fp_line
			(start 0.120396 0.3048)
			(end 0.120396 0.2794)
			(stroke
				(width 0.1)
				(type default)
			)
			(layer "F.Fab")
		)
		(fp_line
			(start 0.12065 -0.3048)
			(end 0.67945 -0.3048)
			(stroke
				(width 0.1)
				(type default)
			)
			(layer "F.Fab")
		)
		(fp_line
			(start 0.12065 -0.2794)
			(end 0.12065 -0.3048)
			(stroke
				(width 0.1)
				(type default)
			)
			(layer "F.Fab")
		)
		(fp_line
			(start 0.67945 -0.3048)
			(end 0.67945 0.3048)
			(stroke
				(width 0.1)
				(type default)
			)
			(layer "F.Fab")
		)
		(fp_line
			(start 0.67945 0.3048)
			(end 0.120396 0.3048)
			(stroke
				(width 0.1)
				(type default)
			)
			(layer "F.Fab")
		)
		(pad "1" smd rect
			(at -0.40005 0 180)
			(size 0.4572 0.508)
			(layers "F.Cu" "F.Mask" "F.Paste")
			(net "P52V_HS2_TEMPP")
		)
		(pad "2" smd rect
			(at 0.40005 0 180)
			(size 0.4572 0.508)
			(layers "F.Cu" "F.Mask" "F.Paste")
			(net "P52V_HS2_TEMP_R")
		)
	)
)
